5
5
4
4
3
3
2
2
1
1
D D
C C
B B
A A
Grand Teton VPDB
Project Name :Grand Teton VPDBPCB Number: PCB REV: FPCB Size: 147 *328 mmPCB Layer: 10LAST UPDATE: 2022/12/27
COVER PAGE
SizeDoc NumberRevDate: SheetofReviewerDesignerDepartmentProject
Page TitleBU9<Doc> AB Thursday, August 24, 2023<Designer><Reviewer> 1 39<Title>COVER PAGESizeDoc NumberRevDate: SheetofReviewerDesignerDepartmentProject
Page TitleBU9<Doc> AB Thursday, August 24, 2023<Designer><Reviewer> 1 39<Title>COVER PAGESizeDoc NumberRevDate: SheetofReviewerDesignerDepartmentProject
Page TitleBU9<Doc> AB Thursday, August 24, 2023<Designer><Reviewer> 1 39<Title>COVER PAGE



5
5
4
4
3
3
2
2
1
1
D D
C C
B B
A A
INDEX
001 COVER PAGE002 PAGE INDEX003 BOARD BLOCK DIAGRAM004 I2C BLOCK DIAGRAM005 POWER BLOCK DIAGRAM006 POWER SEQUENCE DIAGRAM007 BLANK008  I2C ISOLATION009 GPU HSC ENABLE BUFFER010 I2C MUX011 IOEXP012 MB P3V3_AUX PWRGD BUFFER013 GPU HSC PWRGD BUFFER014 FAN POWER ENABLE BUFFER015 I2C RESET BUFFER016 FRU017 POWER MONITOR FOR FAN018 P52V VOLTAGE MONITOR019 P52V VOLTAGE MONITOR 2020 POWER GOOD LEDs021 TO MB CONN022 TO SWITCH BOARD CONN023 48V POWER CONN024 TO HPDB CONN025 HOT SWAP P54V_HS_0
PAGE INDEX
026 HOT SWAP P54V_HS_1027 MOSFET_RSHUNT028 P52V TO P12V BRICK0029 P52V TO P12V BRICK1030 P52V TO P12V BRICK2031 P52V TO P12V BRICK3032 L-C FILTER033 P12V CURRENT LIMIT034 P3V3_AUX035 AC POWER BUTTON036 LOSS COUPON037 DUMMY SYMBOLS038 SCREW HOLES039 TDR
SizeDoc NumberRevDate: SheetofReviewerDesignerDepartmentProject
Page TitleBU9<Doc> AB Thursday, August 24, 2023<Designer><Reviewer> 2 39<Title><Page Title>SizeDoc NumberRevDate: SheetofReviewerDesignerDepartmentProject
Page TitleBU9<Doc> AB Thursday, August 24, 2023<Designer><Reviewer> 2 39<Title><Page Title>SizeDoc NumberRevDate: SheetofReviewerDesignerDepartmentProject
Page TitleBU9<Doc> AB Thursday, August 24, 2023<Designer><Reviewer> 2 39<Title><Page Title>



5
5
4
4
3
3
2
2
1
1
D D
C C
B B
A A
BOARD BLOCK DIAGRAM SizeDoc NumberRevDate: SheetofReviewerDesignerDepartmentProject
Page TitleBU9<Doc> AC Thursday, August 24, 2023<Designer><Reviewer> 3 39<Title><Page Title>SizeDoc NumberRevDate: SheetofReviewerDesignerDepartmentProject
Page TitleBU9<Doc> AC Thursday, August 24, 2023<Designer><Reviewer> 3 39<Title><Page Title>SizeDoc NumberRevDate: SheetofReviewerDesignerDepartmentProject
Page TitleBU9<Doc> AC Thursday, August 24, 2023<Designer><Reviewer> 3 39<Title><Page Title>



5
5
4
4
3
3
2
2
1
1
D D
C C
B B
A A
I2C BLOCK DIAGRAM SizeDoc NumberRevDate: SheetofReviewerDesignerDepartmentProject
Page TitleBU9<Doc> AC Thursday, August 24, 2023<Designer><Reviewer> 4 39<Title><Page Title>SizeDoc NumberRevDate: SheetofReviewerDesignerDepartmentProject
Page TitleBU9<Doc> AC Thursday, August 24, 2023<Designer><Reviewer> 4 39<Title><Page Title>SizeDoc NumberRevDate: SheetofReviewerDesignerDepartmentProject
Page TitleBU9<Doc> AC Thursday, August 24, 2023<Designer><Reviewer> 4 39<Title><Page Title>



5
5
4
4
3
3
2
2
1
1
D D
C C
B B
A A
POWER BLOCK DIAGRAM SizeDoc NumberRevDate: SheetofReviewerDesignerDepartmentProject
Page TitleBU9<Doc> AC Thursday, August 24, 2023<Designer><Reviewer> 5 39<Title><Page Title>SizeDoc NumberRevDate: SheetofReviewerDesignerDepartmentProject
Page TitleBU9<Doc> AC Thursday, August 24, 2023<Designer><Reviewer> 5 39<Title><Page Title>SizeDoc NumberRevDate: SheetofReviewerDesignerDepartmentProject
Page TitleBU9<Doc> AC Thursday, August 24, 2023<Designer><Reviewer> 5 39<Title><Page Title>



5
5
4
4
3
3
2
2
1
1
D D
C C
B B
A A
006 POWER SEQUENCE DIAGRAM SizeDoc NumberRevDate: SheetofReviewerDesignerDepartmentProject
Page TitleBU9<Doc> AC Thursday, August 24, 2023<Designer><Reviewer> 6 39<Title><Page Title>SizeDoc NumberRevDate: SheetofReviewerDesignerDepartmentProject
Page TitleBU9<Doc> AC Thursday, August 24, 2023<Designer><Reviewer> 6 39<Title><Page Title>SizeDoc NumberRevDate: SheetofReviewerDesignerDepartmentProject
Page TitleBU9<Doc> AC Thursday, August 24, 2023<Designer><Reviewer> 6 39<Title><Page Title>



5
5
4
4
3
3
2
2
1
1
D D
C C
B B
A A
SizeDoc NumberRevDate: SheetofReviewerDesignerDepartmentProject
Page TitleBU9<Doc> AB Thursday, August 24, 2023<Designer><Reviewer> 7 39<Title><Page Title>SizeDoc NumberRevDate: SheetofReviewerDesignerDepartmentProject
Page TitleBU9<Doc> AB Thursday, August 24, 2023<Designer><Reviewer> 7 39<Title><Page Title>SizeDoc NumberRevDate: SheetofReviewerDesignerDepartmentProject
Page TitleBU9<Doc> AB Thursday, August 24, 2023<Designer><Reviewer> 7 39<Title><Page Title>



5
5
4
4
3
3
2
2
1
1
D D
C C
B B
A A
 I2C ISOLATION
MB BMC I2C
From MB
CAD Note: Place Resistors near LTC4307
SMB_MB_PDB_SCL21 SMB_PDB_MISC_SCL 10SMB_MB_PDB_SDA21 SMB_PDB_MISC_SDA 10PWRGD_P3V3_AUX_MB_BUF12,24P3V3_AUXP3V3_AUXP3V3_AUX
SizeDoc NumberRevDate: SheetofReviewerDesignerDepartmentProject
Page TitleBU9<Doc> ACustom Thursday, August 24, 2023<Designer><Reviewer> 8 39<Title><Page Title>SizeDoc NumberRevDate: SheetofReviewerDesignerDepartmentProject
Page TitleBU9<Doc> ACustom Thursday, August 24, 2023<Designer><Reviewer> 8 39<Title><Page Title>SizeDoc NumberRevDate: SheetofReviewerDesignerDepartmentProject
Page TitleBU9<Doc> ACustom Thursday, August 24, 2023<Designer><Reviewer> 8 39<Title><Page Title>
R3 05%R0402-0201 1/16WNIR5 331% R0402-02011/16WR7 05% R0402-0201 1/16WR110KR04021%1/16WR4 331% R0402-02011/16WU1LTC4307NIENABLE1SCL_IN3SDA_IN6GND4VCC8SCL_OUT2SDA_OUT7READY5R210KR04021%1/16WR6 05% R0402-0201 1/16WC10.1UF10%16VC0402-0201X7RNISMB_MB_PDB_SCLSMB_PDB_MISC_SCL_RSMB_PDB_MISC_SCLSMB_MB_PDB_SDASMB_PDB_MISC_SDA_RSMB_PDB_MISC_SDAMB_MISC_I2C_ENNC_U1_READY



5
5
4
4
3
3
2
2
1
1
D D
C C
B B
A A
GPU HSC EN BUFFER SizeDoc NumberRevDate: SheetofReviewerDesignerDepartmentProject
Page TitleBU9<Doc> ACustom Thursday, August 24, 2023<Designer><Reviewer> 9 39<Title><Page Title>SizeDoc NumberRevDate: SheetofReviewerDesignerDepartmentProject
Page TitleBU9<Doc> ACustom Thursday, August 24, 2023<Designer><Reviewer> 9 39<Title><Page Title>SizeDoc NumberRevDate: SheetofReviewerDesignerDepartmentProject
Page TitleBU9<Doc> ACustom Thursday, August 24, 2023<Designer><Reviewer> 9 39<Title><Page Title>



5
5
4
4
3
3
2
2
1
1
D D
C C
B B
A A
I2C MUX
ADDRESS 0XE4[1 1 1 0 0 A1 A0 0]
SMB_PDB_MISC_SCL8RST_SMB_PDB_BUF_N15,24SMB_PDB_MISC_SDA8 SMB_VPDB_MISC_SCL 11,16SMB_HPDB_MISC_SCL 24SMB_VPDB_MISC_SDA 11,16SMB_HPDB_MISC_SDA 24SMB_P52V_VPDB_SCL 28,29,30,31SMB_P52V_VPDB_SDA 28,29,30,31SMB_P52V_HPDB_SCL 24SMB_P52V_HPDB_SDA 24SMB_P52V_HSC_SCL 25,26,27SMB_P52V_HSC_SDA 25,26,27P3V3_AUXP3V3_AUXP3V3_AUXP3V3_AUXP3V3_AUXP3V3_AUXP3V3_AUXP3V3_AUXP3V3_AUXP3V3_AUXP3V3_AUXP3V3_AUXP3V3_AUXP3V3_AUXP3V3_AUX
SizeDoc NumberRevDate: SheetofReviewerDesignerDepartmentProject
Page TitleBU9<Doc> AB Thursday, August 24, 2023<Designer><Reviewer> 10 39<Title><Page Title>SizeDoc NumberRevDate: SheetofReviewerDesignerDepartmentProject
Page TitleBU9<Doc> AB Thursday, August 24, 2023<Designer><Reviewer> 10 39<Title><Page Title>SizeDoc NumberRevDate: SheetofReviewerDesignerDepartmentProject
Page TitleBU9<Doc> AB Thursday, August 24, 2023<Designer><Reviewer> 10 39<Title><Page Title>
R981KR0402-02011%1/16WNI R13110KR04021%1/16WR184 331% R0402-02011/16WR1021KR0402-02011%1/16WC480.1UF10%16VC0402-0201X7RR12910KR04021%1/16WR1054.7KR0402-02015%1/16WR5878 331% R0402-02011/16WR13210KR04021%1/16WR12510KR04021%1/16WR1064.7KR0402-02015%1/16WR13010KR04021%1/16WR5879 331% R0402-02011/16WR113 05%R0402-02011/16WR971KR0402-02011%1/16WR1014.7KR0402-02015%1/16WR12710KR04021%1/16WU25PCA9545APWA01A12RESET#3INT#17SCL18SDA19VSS10VDD20SD05SC06INT0#4SD18SC19INT1#7SD212SC213INT2#11SD315SC316INT3#14R1031KR0402-02011%1/16WNIR12610KR04021%1/16WR1004.7KR0402-02015%1/16WR12810KR04021%1/16WTP_9543_MISC_INT_NRST_SMB_PDB_BUF_R1_NPCA9543_MISC_A1PCA9543_MISC_A0PU_9543_0_INT0PU_9543_0_INT1SMB_P52V_VPDB_SCL_RPU_9543_1_INT0PU_9543_1_INT1



5
5
4
4
3
3
2
2
1
1
D D
C C
B B
A A
IOEXP
ADDRESS 0X44[0 1 0 0 A2 A1 A0 0]
SKU ID
EVT
STAGE
PO
BOARD_ID_2
0
BOARD ID
BOARD_ID_1
0
BOARD_ID_0
0
0 0 1
EVT2 0 1 0
SKU_ID_2
0
1
HSC
LTC4287
ADM1272
DVT 0 1 1
BRICK SKU_ID_1
DELTA
FLEX
0
1
DVT2 1 0 0
PVT 1 1 0
SMB_VPDB_MISC_SDA10,16SMB_VPDB_MISC_SCL10,16P12V_BRICK0_ALERT_N 28P12V_BRICK1_ALERT_N 29P12V_BRICK2_ALERT_N 30P12V_BRICK3_ALERT_N 31P52V_HS1_FLT 25,26PWRGD_P3V3_HPDB 24PRSNT_HPDB_N 24P12V_HPDB_PWRGD 24,33P3V3_AUXP3V3_AUXP3V3_AUXP3V3_AUXP3V3_AUXP3V3_AUXP3V3_AUXP3V3_AUXP3V3_AUXP3V3_AUXP3V3_AUXSizeDoc NumberRevDate: SheetofReviewerDesignerDepartmentProject
Page TitleBU9<Doc> AC Thursday, August 24, 2023<Designer><Reviewer> 11 39<Title><Page Title>SizeDoc NumberRevDate: SheetofReviewerDesignerDepartmentProject
Page TitleBU9<Doc> AC Thursday, August 24, 2023<Designer><Reviewer> 11 39<Title><Page Title>SizeDoc NumberRevDate: SheetofReviewerDesignerDepartmentProject
Page TitleBU9<Doc> AC Thursday, August 24, 2023<Designer><Reviewer> 11 39<Title><Page Title>R1341KR0402-02011%1/16WNIR921KR0402-02011%1/16WNIR221KR0402-02011%1/16WNIR1371KR0402-02011%1/16WR951KR0402-02011%1/16WR1351KR0402-02011%1/16WR1381KR0402-02011%1/16WNIR174.7KR0402-02015%1/16WR231KR0402-02011%1/16WR191KR0402-02011%1/16WR117 331% R0402-02011/16WR201KR0402-02011%1/16WNIR211KR0402-02011%1/16WR901KR0402-02011%1/16WHSC1_BOM2R931KR0402-02011%1/16WHSC1_BOM1R1331KR0402-02011%1/16WR181KR0402-02011%1/16WNIU4PCA9555VDD24VSS12INT1SDA23SCL22P004P015P026P037P048P059P0610P0711P1013P1114P1215P1316P1417P1518P1619P1720A021A12A23 R911KR0402-02011%1/16WBRICK_FLEXR1361KR0402-02011%1/16WNIC40.1UF10%16VC0402-0201X7RR118 331% R0402-02011/16WR941KR0402-02011%1/16WBRICK_DELTAPU_U4_PIN1PCA9555_A0PCA9555_A1PCA9555_A2SMB_VPDB_IOEXP_SDASMB_VPDB_IOEXP_SCLPCA9555_A0PCA9555_A1PCA9555_A2TP_U4_P05SKU_ID_2SKU_ID_1SKU_ID_0SKU_ID_0SKU_ID_1SKU_ID_2TP_U4_P06BOARD_ID_0BOARD_ID_1BOARD_ID_2BOARD_ID_2BOARD_ID_1BOARD_ID_0



5
5
4
4
3
3
2
2
1
1
D D
C C
B B
A A
MB P3V3_AUX PWRGD BUFFER
CAD Note: Place Resistors near 74LVC1G07SE-7
MB P3V3_AUX PWRGD
PWRGD_P3V3_AUX_MB21 PWRGD_P3V3_AUX_MB_BUF 8,12,24PWRGD_P3V3_AUX_MB_BUF_N 14,15PWRGD_P3V3_AUX_MB_BUF8,12,24P3V3_AUXP3V3_AUXP3V3_AUX
SizeDoc NumberRevDate: SheetofReviewerDesignerDepartmentProject
Page TitleBU9<Doc> ACustom Thursday, August 24, 2023<Designer><Reviewer> 12 39<Title><Page Title>SizeDoc NumberRevDate: SheetofReviewerDesignerDepartmentProject
Page TitleBU9<Doc> ACustom Thursday, August 24, 2023<Designer><Reviewer> 12 39<Title><Page Title>SizeDoc NumberRevDate: SheetofReviewerDesignerDepartmentProject
Page TitleBU9<Doc> ACustom Thursday, August 24, 2023<Designer><Reviewer> 12 39<Title><Page Title>
D
G
S
U202N7002KDGSC50.1UF10%16VC0402-0201X7RR140100KR0402-02015%1/16WR27 05% R0402-02011/16WU574LVC1G126SE-724531R1424.7KR0402-02015%1/16WR187100KR0402-02015%1/16WR244.7K5%R0402-02011/16WR141 1501% R0402-02011/16WPWRGD_P3V3_AUX_MB_R1PWRGD_P3V3_AUX_MB_BUF_RPWRGD_P3V3_AUX_MB_BUFPWRGD_P3V3_AUX_MB_BUF_NPWRGD_P3V3_AUX_MB_BUFFM_U5_VCC



5
5
4
4
3
3
2
2
1
1
D D
C C
B B
A A
GPU HSC PWRGD BUFFER
CAD NOTE:
GPU HSC PWRGD
CAD Note: Place Resistors near BUFFER
Place Bufferclose to MB Conn
PWRGD_GPU_HSC24 PWRGD_GPU_HSC_BUF_R 21P3V3_AUXP3V3_AUXP3V3_AUX
SizeDoc NumberRevDate: SheetofReviewerDesignerDepartmentProject
Page TitleBU9<Doc> ACustom Thursday, August 24, 2023<Designer><Reviewer> 13 39<Title><Page Title>SizeDoc NumberRevDate: SheetofReviewerDesignerDepartmentProject
Page TitleBU9<Doc> ACustom Thursday, August 24, 2023<Designer><Reviewer> 13 39<Title><Page Title>SizeDoc NumberRevDate: SheetofReviewerDesignerDepartmentProject
Page TitleBU9<Doc> ACustom Thursday, August 24, 2023<Designer><Reviewer> 13 39<Title><Page Title>
R189 05% R0402-02011/16WR185 05% R0402-02011/16WR30 05% R0402-02011/16WNIR2810KR0402-02015%1/16WNIC70.1UFX7R16VC0402-020110%NIR188100KR0402-02015%1/16WU674LVC1G07SE-7NIVCC5A2GND3Y4NC11R2910KR0402-02015%1/16WNIPWRGD_GPU_HSCPWRGD_GPU_HSC_BUFPWRGD_GPU_HSC_BUF_RNC_U6PWRGD_GPU_HSC_R



5
5
4
4
3
3
2
2
1
1
D D
C C
B B
A A
FAN POWER ENABLE BUFFER
FAN PWR EN MB
FAN_PWR_EN21 FAN_PWR_EN_BUF 24PWRGD_P3V3_AUX_MB_BUF_N 12,15P3V3_AUXP3V3_AUX
SizeDoc NumberRevDate: SheetofReviewerDesignerDepartmentProject
Page TitleBU9<Doc> ACustom Thursday, August 24, 2023<Designer><Reviewer> 14 39<Title><Page Title>SizeDoc NumberRevDate: SheetofReviewerDesignerDepartmentProject
Page TitleBU9<Doc> ACustom Thursday, August 24, 2023<Designer><Reviewer> 14 39<Title><Page Title>SizeDoc NumberRevDate: SheetofReviewerDesignerDepartmentProject
Page TitleBU9<Doc> ACustom Thursday, August 24, 2023<Designer><Reviewer> 14 39<Title><Page Title>
3 state outputU874LVC1G125GV<Part Number>24513R59034.7K5%R0402-02011/16WR32 0R0402-02015% 1/16WC8 0.1UFX7R 16V C0402-0201R33100KR0402-02015%1/16WFAN_PWR_ENFAN_PWR_EN_BUF_RFAN_PWR_EN_BUF



5
5
4
4
3
3
2
2
1
1
D D
C C
B B
A A
I2C RESET BUFFER
I2C RESET
CAD NOTE:
Place Bufferclose to MB Conn
PWRGD_P3V3_AUX_MB_BUF_N 12,14RST_SMB_PDB_N21 RST_SMB_PDB_BUF_N 10,24P3V3_AUXP3V3_AUX
SizeDoc NumberRevDate: SheetofReviewerDesignerDepartmentProject
Page TitleBU9<Doc> AB Thursday, August 24, 2023<Designer><Reviewer> 15 39<Title><Page Title>SizeDoc NumberRevDate: SheetofReviewerDesignerDepartmentProject
Page TitleBU9<Doc> AB Thursday, August 24, 2023<Designer><Reviewer> 15 39<Title><Page Title>SizeDoc NumberRevDate: SheetofReviewerDesignerDepartmentProject
Page TitleBU9<Doc> AB Thursday, August 24, 2023<Designer><Reviewer> 15 39<Title><Page Title>
R35 200R0402-02011%1/16W<Part Number>C9 0.1UFX7R 16V C0402-0201R3410KR0402-02015%1/16W3 state outputU974LVC1G125GV24513RST_SMB_PDB_BUF_R_N



5
5
4
4
3
3
2
2
1
1
D D
C C
B B
A A
FRU
FRU
ADDRESS 0XA4
SMB_VPDB_MISC_SDA 10,11SMB_VPDB_MISC_SCL 10,11P3V3_AUXP3V3_AUXP3V3_AUX
SizeDoc NumberRevDate: SheetofReviewerDesignerDepartmentProject
Page TitleBU9<Doc> AB Thursday, August 24, 2023<Designer><Reviewer> 16 39<Title><Page Title>SizeDoc NumberRevDate: SheetofReviewerDesignerDepartmentProject
Page TitleBU9<Doc> AB Thursday, August 24, 2023<Designer><Reviewer> 16 39<Title><Page Title>SizeDoc NumberRevDate: SheetofReviewerDesignerDepartmentProject
Page TitleBU9<Doc> AB Thursday, August 24, 2023<Designer><Reviewer> 16 39<Title><Page Title>
C100.1UFC0402-020110%16VX7RR404.7KR0402-02015%NIR45220R0402-02015%R394.7KR0402-02015%R361K1/16W1%R0402-0201NIU10M24256-BRMN6TPWC_N7E01E12E23SDA5SCL6VCC8VSS4R44220R0402-02015%NIR43220R0402-02015%R41 331% R0402-02011/16WR42 331% R0402-02011/16WR384.7KR0402-02015%NIR3710K1/16W5%R0402-0201SMB_VPDB_MISC_SDASMB_FRU_DATSMB_VPDB_MISC_SCLSMB_FRU_CLKFRU_ADDR0FRU_ADDR2FRU_ADDR1FRU_WP_N



5
5
4
4
3
3
2
2
1
1
D D
C C
B B
A A
POWER MONITOR FOR FAN
P52V_HSP52V_FAN
SizeDoc NumberRevDate: SheetofReviewerDesignerDepartmentProject
Page TitleBU9<Doc> AB Thursday, August 24, 2023<Designer><Reviewer> 17 39<Title><Page Title>SizeDoc NumberRevDate: SheetofReviewerDesignerDepartmentProject
Page TitleBU9<Doc> AB Thursday, August 24, 2023<Designer><Reviewer> 17 39<Title><Page Title>SizeDoc NumberRevDate: SheetofReviewerDesignerDepartmentProject
Page TitleBU9<Doc> AB Thursday, August 24, 2023<Designer><Reviewer> 17 39<Title><Page Title>
R58730.0005<Part Number>2WR2512_4P1234



5
5
4
4
3
3
2
2
1
1
D D
C C
B B
A A
SizeDoc NumberRevDate: SheetofReviewerDesignerDepartmentProject
Page TitleBU9<Doc> AB Thursday, August 24, 2023<Designer><Reviewer> 18 39<Title><Page Title>SizeDoc NumberRevDate: SheetofReviewerDesignerDepartmentProject
Page TitleBU9<Doc> AB Thursday, August 24, 2023<Designer><Reviewer> 18 39<Title><Page Title>SizeDoc NumberRevDate: SheetofReviewerDesignerDepartmentProject
Page TitleBU9<Doc> AB Thursday, August 24, 2023<Designer><Reviewer> 18 39<Title><Page Title>



5
5
4
4
3
3
2
2
1
1
D D
C C
B B
A A
VOLTAGE/CURRENT MON ADC 2 SizeDoc NumberRevDate: SheetofReviewerDesignerDepartmentProject
Page TitleBU9<Doc> AB Thursday, August 24, 2023<Designer><Reviewer> 19 39<Title><Page Title>SizeDoc NumberRevDate: SheetofReviewerDesignerDepartmentProject
Page TitleBU9<Doc> AB Thursday, August 24, 2023<Designer><Reviewer> 19 39<Title><Page Title>SizeDoc NumberRevDate: SheetofReviewerDesignerDepartmentProject
Page TitleBU9<Doc> AB Thursday, August 24, 2023<Designer><Reviewer> 19 39<Title><Page Title>



5
5
4
4
3
3
2
2
1
1
D D
C C
B B
A A
POWER GOOD LEDs
P12V_LEDP52V_LED P3V3_LED
P52V_HSP12V_BRICKP3V3_AUX
SizeDoc NumberRevDate: SheetofReviewerDesignerDepartmentProject
Page TitleBU9<Doc> ACustom Thursday, August 24, 2023<Designer><Reviewer> 20 39<Title><Page Title>SizeDoc NumberRevDate: SheetofReviewerDesignerDepartmentProject
Page TitleBU9<Doc> ACustom Thursday, August 24, 2023<Designer><Reviewer> 20 39<Title><Page Title>SizeDoc NumberRevDate: SheetofReviewerDesignerDepartmentProject
Page TitleBU9<Doc> ACustom Thursday, August 24, 2023<Designer><Reviewer> 20 39<Title><Page Title>D1LED_BLUEACR631K5%1/4WR1206XNR601K5%1/4WR1206XNR583161/16W1%R0402-0201R621K5%1/4WR1206XNR613161/16W1%R0402-0201D3LED_BLUEACD2LED_BLUEAC
R563161/16W1%R0402-0201R551K5%1/4WR1206XNR59751%1/16W<Part Number>R0402-0201R571K5%1/4WR1206XNLED_D2_R3LED_D1_R5LED_D1_R1LED_D1_R2LED_D1_R3LED_D1_R4LED_D2_R1LED_D2_R2LED_D3_R



5
5
4
4
3
3
2
2
1
1
D D
C C
B B
A A
TO MB CONN
RST_SMB_PDB_N15PWRGD_P3V3_AUX_MB12 SMB_MB_PDB_SDA 8FAN_PWR_EN 14GPU_HSC_EN 24SMB_MB_PDB_SCL 8PWRGD_GPU_HSC_BUF_R 13P12V_BRICK_PWRGD29,30,31,33FM_AC_PWR_CYCLE_N35P12V_BRICKP3V3_AUXP3V3_AUX
SizeDoc NumberRevDate: SheetofReviewerDesignerDepartmentProject
Page TitleBU9<Doc> AB Thursday, August 24, 2023<Designer><Reviewer> 21 39<Title><Page Title>SizeDoc NumberRevDate: SheetofReviewerDesignerDepartmentProject
Page TitleBU9<Doc> AB Thursday, August 24, 2023<Designer><Reviewer> 21 39<Title><Page Title>SizeDoc NumberRevDate: SheetofReviewerDesignerDepartmentProject
Page TitleBU9<Doc> AB Thursday, August 24, 2023<Designer><Reviewer> 21 39<Title><Page Title>
SIGNAL
POWERCONN60_10106267-6003502LFJ1A2A2B2B2C2C2D2D2P1_1P1_1P1_2P1_2P1_3P1_3P1_4P1_4P1_5P1_5P1_6P1_6P1_7P1_7P1_8P1_8P2_1P2_1P2_2P2_2P2_3P2_3P2_4P2_4P2_5P2_5P2_6P2_6P2_7P2_7P2_8P2_8P4_1P4_1P4_2P4_2P4_3P4_3P4_4P4_4P4_5P4_5P4_6P4_6P4_7P4_7P4_8P4_8A1A1B1B1C1C1D1D1P5_1P5_1P5_2P5_2P5_3P5_3P5_4P5_4P5_5P5_5P5_6P5_6P5_7P5_7P5_8P5_8P3_1P3_1P3_2P3_2P3_3P3_3P3_4P3_4P3_5P3_5P3_6P3_6P3_7P3_7P3_8P3_8P6_1P6_1P6_2P6_2P6_3P6_3P6_4P6_4P6_5P6_5P6_6P6_6P6_7P6_7P6_8P6_8A3A3B3B3C3C3D3D3R96 1001/16W1%R0402-0201
C17 0.1UFX7R 16V C0402-0201NI
R70 33R0402-02011% 1/16W
R75 4.7KR0402-02015% 1/16W NIC15 0.1UFX7R 16V C0402-0201NI
R5904 05% R0402-0201
C14 0.1UFX7R 16V C0402-0201NIC66 0.1UFX7R 16V C0402-0201NIC47 0.1UFX7R 16V C0402-0201NI
R139 33R0402-02011% 1/16WR65 0R04025% 1/16W
C18 0.1UFX7R 16V C0402-0201NI
R71 100R0402-02011% 1/16W
D
G
S
U27DMN53D0L-7DGSC16 0.1UFX7R 16V C0402-0201NI
R199 05% R0402-0201R67 0R04025% 1/16W
R74 4.7KR0402-02015% 1/16W NIC67 0.1UFX7R 16V C0402-0201NI
R69 301R0402-02011% 1/16WTP_J1_A1FM_AC_PWR_CYCLE_R_NRST_SMB_PDB_R_NPWRGD_P3V3_AUX_MB_RSMB_MB_PDB_R_SCLSMB_MB_PDB_R_SDAFAN_PWR_R_ENGPU_HSC_R_ENPWRGD_GPU_HSC_BUF_R
SMB_MB_PDB_R_SCLSMB_MB_PDB_R_SDARST_SMB_PDB_R_NPWRGD_P3V3_AUX_MB_RPWRGD_GPU_HSC_BUF_RFAN_PWR_R_ENGPU_HSC_R_EN
P3V3_AUX_SCALEDP12V_BRICK_PWRGD_R_NP12V_BRICK_PWRGD_N
P12V_BRICK_PWRGD_R_NSMB_MB_PDB_R_SCLSMB_MB_PDB_R_SDAP12V_BRICK_PWRGD_N



5
5
4
4
3
3
2
2
1
1
D D
C C
B B
A A
TO SW BOARD CONN
P12V_BRICK
SizeDoc NumberRevDate: SheetofReviewerDesignerDepartmentProject
Page TitleBU9<Doc> ACustom Thursday, August 24, 2023<Designer><Reviewer> 22 39<Title><Page Title>SizeDoc NumberRevDate: SheetofReviewerDesignerDepartmentProject
Page TitleBU9<Doc> ACustom Thursday, August 24, 2023<Designer><Reviewer> 22 39<Title><Page Title>SizeDoc NumberRevDate: SheetofReviewerDesignerDepartmentProject
Page TitleBU9<Doc> ACustom Thursday, August 24, 2023<Designer><Reviewer> 22 39<Title><Page Title>
CONN48_10106267-6000402LFJ2P1_1P1_1P1_2P1_2P1_3P1_3P1_4P1_4P1_5P1_5P1_6P1_6P1_7P1_7P1_8P1_8P2_1P2_1P2_2P2_2P2_3P2_3P2_4P2_4P2_5P2_5P2_6P2_6P2_7P2_7P2_8P2_8P4_1P4_1P4_2P4_2P4_3P4_3P4_4P4_4P4_5P4_5P4_6P4_6P4_7P4_7P4_8P4_8P5_1P5_1P5_2P5_2P5_3P5_3P5_4P5_4P5_5P5_5P5_6P5_6P5_7P5_7P5_8P5_8P3_1P3_1P3_2P3_2P3_3P3_3P3_4P3_4P3_5P3_5P3_6P3_6P3_7P3_7P3_8P3_8P6_1P6_1P6_2P6_2P6_3P6_3P6_4P6_4P6_5P6_5P6_6P6_6P6_7P6_7P6_8P6_8



5
5
4
4
3
3
2
2
1
1
D D
C C
B B
A A
P52V POWER CONNECTOR
P52V_BUSBAR27P52V_1P52V_1P52V_1P52V_1_R
SizeDoc NumberRevDate: SheetofReviewerDesignerDepartmentProject
Page TitleBU9<Doc> AB Thursday, August 24, 2023<Designer><Reviewer> 23 39<Title><Page Title>SizeDoc NumberRevDate: SheetofReviewerDesignerDepartmentProject
Page TitleBU9<Doc> AB Thursday, August 24, 2023<Designer><Reviewer> 23 39<Title><Page Title>SizeDoc NumberRevDate: SheetofReviewerDesignerDepartmentProject
Page TitleBU9<Doc> AB Thursday, August 24, 2023<Designer><Reviewer> 23 39<Title><Page Title>
R5890 01/8W <Part Number>J5CONN36_10106267-4001501LFP4_1P4_1P4_2P4_2P4_3P4_3P4_4P4_4P4_5P4_5P4_6P4_6P4_7P4_7P4_8P4_8P2_1P2_1P2_2P2_2P2_3P2_3P2_4P2_4P2_5P2_5P2_6P2_6P2_7P2_7P2_8P2_8P1_1P1_1P1_2P1_2P1_3P1_3P1_4P1_4P1_5P1_5P1_6P1_6P1_7P1_7P1_8P1_8P3_1P3_1P3_2P3_2P3_3P3_3P3_4P3_4P3_5P3_5P3_6P3_6P3_7P3_7P3_8P3_8A1A1B1B1C1C1D1D1GND_BUSBARTP_J5_C1TP_J5_D1



5
5
4
4
3
3
2
2
1
1
D D
C C
B B
A A
TO HPDB CONN
SMB_HPDB_MISC_SCL10SMB_HPDB_MISC_SDA10SMB_P52V_HPDB_SCL10SMB_P52V_HPDB_SDA10GPU_HSC_EN 21RST_SMB_PDB_BUF_N 10,15FAN_PWR_EN_BUF 14PWRGD_P3V3_AUX_MB_BUF 8,12PWRGD_GPU_HSC13P12V_HPDB_PWRGD 11,33PRSNT_HPDB_N11PWRGD_P3V3_HPDB11P12V_HPDBP52V_FANP3V3_AUXP52V_FAN
SizeDoc NumberRevDate: SheetofReviewerDesignerDepartmentProject
Page TitleBU9<Doc> ACustom Thursday, August 24, 2023<Designer><Reviewer> 24 39<Title><Page Title>SizeDoc NumberRevDate: SheetofReviewerDesignerDepartmentProject
Page TitleBU9<Doc> ACustom Thursday, August 24, 2023<Designer><Reviewer> 24 39<Title><Page Title>SizeDoc NumberRevDate: SheetofReviewerDesignerDepartmentProject
Page TitleBU9<Doc> ACustom Thursday, August 24, 2023<Designer><Reviewer> 24 39<Title><Page Title>
R77 0R0402-02015% 1/16WR590910KR0402-02015%1/16WR78 0R0402-02015% 1/16WR79 0R0402-02015% 1/16WR76 0R0402-02015% 1/16WJ14CONN1_10045597-101LFSCR_H1J7CONN32_10164834-002QLFS2S2S3S3S1S1S7S7S8S8S4S4S5S5S6S6P4P4P3P3P2P2P1P1P5P5P6P6P7P7P8P8P9P9P10P10P11P11P12P12P13P13P14P14P15P15P16P16S9S9S10S10S11S11S12S12S13S13S14S14S15S15S16S16J15CONN1_10045597-101LFSCR_H1SMB_HPDB_MISC_R_SCLSMB_HPDB_MISC_R_SDASMB_P52V_HPDB_R_SCLSMB_P52V_HPDB_R_SDAPRSNT_HPDB_N



5
5
4
4
3
3
2
2
1
1
D D
C C
B B
A A
HSC OCP= 51V / 121A (6160W)
Current limit threshold :18mV
52V HOT SWAP_LTC4287
36.269 37.736
53.675
typical
36.815
59.676
Rising UVLO 43.91
39.68
40.726
56.719
Rising PG
Falling PG
Falling OVLO
min.
45.62
38.184
55.557
Falling UVLO
57.756
41.22
42.25
 UV/OV/PG Thresholds
Rising OVLO
38.487 40.209
60.251
max.
Unit: V
SMB Address:0x44(7bit),0x88(8bit)              ADR0=MCADR1=NC
P52V_HS1_EN_BUF_DELAY26,35PWRGD_P52V_HS1_PG_N 28P52V_HS1_ADR025,26P52V_HS1_ADR125,26P52V_HS1_FLT 11,26P52V_HS1_TEMP 27P52V_HS1_OV26,27P52V_HS1_UVLO_EN26,27P52V_HS1_4287_GATE_R 27SMB_P52V_HSC_SCL10,26,27SMB_P52V_HSC_SDA10,26,27P52V_HS1_4287_GATE2_R 27P52V_HS_4287_S1P 27P52V_HS_4287_S1N 27P52V_HS_4287_ADC_P 27P52V_HS_4287_ADC_N 27P52V_HS_4287_S2P 27P52V_HS_4287_S2N 27
P52V_HS1_ADR0 25,26P52V_HS1_ADR1 25,26
P52V_HS1_INTVCCP52V_HSP52V_HS1_INTVCCP52V_HS1_INTVCCP52V_1_RP52V_HS
P52V_HS1_DVCCP52V_HS1_DVCCP52V_HS
P52V_HS1_INTVCCGND_FIELD_SIGNALSizeDoc NumberRevDate: SheetofReviewerDesignerDepartmentProject
Page TitleBU9<Doc> AC Thursday, August 24, 2023<Designer><Reviewer> 25 39<Title><Page Title>SizeDoc NumberRevDate: SheetofReviewerDesignerDepartmentProject
Page TitleBU9<Doc> AC Thursday, August 24, 2023<Designer><Reviewer> 25 39<Title><Page Title>SizeDoc NumberRevDate: SheetofReviewerDesignerDepartmentProject
Page TitleBU9<Doc> AC Thursday, August 24, 2023<Designer><Reviewer> 25 39<Title><Page Title>
PC61000PF5%50VC0402-0201<Part Number>X7RHSC1_BOM1PC50.1UF25V10%C0402-0201X7R<Part Number>HSC1_BOM1PC820.033UFC060310%100V<Part Number>X7RHSC1_BOM1
PC48747UF6.3V20%C1206_H76X6S<Part Number>NILTC4287AUK#TRPBFPU11SOURCE2GATE23GATE1ADC-4SENSE1-5SENSE1+6ADC+7SENSE2-8SENSE2+9VDD10UV11OV12INTVCC13GND14DVCC15ADR016ADR117NC118MODE19TMR20CLKIN21CLKOUT22EN||EN#23SIO24SCK2526CS#SCL27SDAI28SDAO29GPIO830GPIO731GPIO632GPIO533GPIO434GPIO335GPIO236GPIO137FB38VDSFB3940TH_GNDR59070<Part Number>R0402-02015%NIR59050<Part Number>R0402-02015%NIPC72200PF50V10%C0402-0201X7R<Part Number>HSC1_BOM1PR21310KNIR0402-02011%1/16W<Part Number>PR220 100NIR0603_H24PR2713KR0402-02011%1/16W<Part Number>HSC1_BOM1PR2412K<Part Number>1%1/16WR0402-0201HSC1_BOM1PR25499K<Part Number>1%1/8WR0805_H26HSC1_BOM1PC830.68UF16V10%C0603X7R<Part Number>NIPR2633K<Part Number>1%1/16WR0402HSC1_BOM1
U29M95256-RDW6TPNIS#1Q2W#3VSS4D5C6HOLD#7VCC8
PC31UF100V10%C1206_H66X7R<Part Number>HSC1_BOM1
R59080<Part Number>R0402-02015%NIPR2875KR0402-02011%1/16W<Part Number>HSC1_BOM1PD151N4448WS-7-FSOD323<Part Number>HSC1_BOM112PC553 0.22UFNIPC80.1UF100VC0603X7R<Part Number>10%HSC1_BOM1
R59060<Part Number>R0402-02015%NIPC5510.056UF16V10% C0402-0201X7R<Part Number>NIPR6971 100NIR0603_H24PD141N4448WS-7-FSOD323<Part Number>HSC1_BOM112PR697033K<Part Number>1%1/16WR0402HSC1_BOM1R5855 0R0402-02015%HSC1_BOM1PR2111M<Part Number>1%1/16WR0402-0201NIPC5650.22UFNIPJ1SHORTHSC1_BOM11122PR23174K<Part Number>1%1/8WR0805HSC1_BOM1PR210 01/16W 5%R0402-0201<Part Number>NIR5864 0R0402-02015%HSC1_BOM1PR21410KHSC1_BOM1R0402-02011%1/16W <Part Number>PC41UF16V10%C0402-0201X6S <Part Number>HSC1_BOM1R5856 0R0402-02015%HSC1_BOM1PR2090HSC1_BOM1PR110HSC1_BOM1PC5640.033UFC060310%100V<Part Number>X7RHSC1_BOM1PR21210KHSC1_BOM1R0402-02011%1/16W<Part Number>PC5630.1UF100VC0603X7R<Part Number>10%HSC1_BOM1PR3301/16W5%R0402-0201<Part Number>NIP52V_HS1_DVCCP52V_HS1_OVP52V_HS1_4287_GATE2_RP52V_HS1_UVLO_ENP52V_HS1_GATE_RCP52V_HS1_TEMPSMB_P52V_VPDB_SCL_R3SMB_P52V_HS1_SDAISMB_P52V_HS1_SDAOP52V_HS1_VDSFBP52V_HS1_SIOP52V_HS1_CSP52V_HS1_FBP52V_HS1_MODEP52V_HS1_TMRHS1_TMR1HS1_TMR2P52V_HS1_CLKINP52V_HS1_SCKP52V_HS1_CSP52V_HS1_SIOP52V_HS1_DVCCP52V_HS1_SCKP52V_HS1_SIOP52V_HS1_4287_GATE_RP52V_HS1_4287_GATE2_RCP52V_HS1_GATE2_R1P52V_HS1_GATE_R1
P52V_HS1_ADR0P52V_HS1_ADR1



5
5
4
4
3
3
2
2
1
1
D D
C C
B B
A A
39.04
Rising OVLO
Falling PG
56.54
41.893
58.27
38.360
58.75
Unit: V
57.02
42.63
60.54
44.44343.168
41.42
Rising UVLO
52V HOT SWAP_ADM1272
min.
60.06
40.21
Falling OVLO
typical
 UV/OV/PG Thresholds
Rising PG
39.710
44.49
41.060Falling UVLO
max.
40.82
OCP = 120A
SMB Address:0x10(7bit),0x20(8bit)              ADR0=0ADR1=0
P52V_HS1_EN_BUF_DELAY25,35PWRGD_P52V_HS1_PG 28P52V_HS1_ADR025,26P52V_HS1_ADR125,26SMB_P52V_VPDB_SCL_R226SMB_P52V_HSC_SDA10,25,27SMB_P52V_HSC_SCL10,25,27SMB_P52V_VPDB_SCL_R2 26P52V_HS1_FLT 11,25P52V_HS1_ADR0 25,26P52V_HS1_ADR1 25,26
P52V_HS1_TEMPP 27P52V_HS1_TEMPN 27P52V_HS1_UVLO_EN25,27P52V_HS1_OV25,27P52V_HS_1272_S_P27P52V_HS_1272_S_N27P52V_HS1_1272_GATE27P52V_1GND_FIELD_SIGNALGND_FIELD_SIGNALP52V_HSP52V_1P52V_HSP52V_HS1_VCCP52V_HSGND_FIELD_SIGNALGND_FIELD_SIGNALP52V_HS1_VCAPGND_FIELD_SIGNALGND_FIELD_SIGNALP3V3_AUXP52V_HS1_VCCGND_FIELD_SIGNALGND_FIELD_SIGNALGND_FIELD_SIGNALP3V3_AUXP3V3_AUXP52V_HS1_VCAPGND_FIELD_SIGNALSizeDoc NumberRevDate: SheetofReviewerDesignerDepartmentProject
Page TitleBU9<Doc> AC Thursday, August 24, 2023<Designer><Reviewer> 26 39<Title><Page Title>SizeDoc NumberRevDate: SheetofReviewerDesignerDepartmentProject
Page TitleBU9<Doc> AC Thursday, August 24, 2023<Designer><Reviewer> 26 39<Title><Page Title>SizeDoc NumberRevDate: SheetofReviewerDesignerDepartmentProject
Page TitleBU9<Doc> AC Thursday, August 24, 2023<Designer><Reviewer> 26 39<Title><Page Title>
R148174K1%R0805_H26<Part Number>HSC1_BOM2PC5580.1UFC1206_H42100VX7R<Part Number>HSC1_BOM2PC128200PF25VC0402-0201X7R<Part Number>HSC1_BOM2R1504.7K<Part Number>R0402-02015%HSC1_BOM2R1560<Part Number>R0402-02015%NIR1464.7K<Part Number>R0402-02015%NI PR35100KR0402-02011%HSC1_BOM2R1530R0402-02015%<Part Number>NIPR36330KR0402-02011%<Part Number>NIPR182.05M<Part Number>1%R0805_H26NIPR51005%<Part Number>R1206XNHSC1_BOM2R144 0R0402-02015%HSC1_BOM2PR3116.9K1%R0402-0201<Part Number>HSC1_BOM2PR693343.2K<Part Number>R0402-02011%HSC1_BOM2PC5610.01UFC0402-020150V<Part Number>X7RHSC1_BOM2PC130.047UF<Part Number>C0805_H57100VX7RHSC1_BOM2R1570<Part Number>R0402-02015%NIR1510R0402-02015%<Part Number>HSC1_BOM2R1474.7K<Part Number>R0402-02015%NI PR1795.3K1%R0805_H26<Part Number>HSC1_BOM2PR37390K1%R0402-0201<Part Number>HSC1_BOM2PR192.05MR0805_H261%HSC1_BOM2<Part Number>PR3220KR0805_H261%<Part Number>HSC1_BOM2PR6934100KR0402-02011%HSC1_BOM2<Part Number>PR693571.5KR0402-02011%<Part Number>NIR81 05%R0402-0201 1/16WHSC1_BOM2
PR69312.26K<Part Number>R0402-02011%HSC1_BOM2
R1580<Part Number>R0402-02015%HSC1_BOM2R145 0R0402-02015%HSC1_BOM2PC5570.1UFC0402-0201<Part Number>25VX7RHSC1_BOM2R14911.5K<Part Number>R0402-02011%HSC1_BOM2PU7ADM1272-1ACPZ-RLHSC1_BOM2VOUT31GATE32SENSE-38VCC41DNC226UVH45UVL46GND19SDAI10SDAO11SCL9RND48TEMP+44MCB12ADR18ADR07VREG42ISTART2PWRGIN18DVDT30VCAP3DNC125PWRGD17NC524OV47ISET1DNC327DNC428DNC533DNC634DNC735DNC836DNC937DNC1040NC423NC322NC221NC120TEMP-43EFAULT5ESTART4ENABLE6GPO114GPO213VCP29FAULT#15RESTART#16SENSE+39EPGNDPAD1EPVCCPAD2PR201KR0402-0201HSC1_BOM2<Part Number>1%PC90.1UFC0402-020125VX7R<Part Number>HSC1_BOM2PR2148.7K1%R0402-0201<Part Number>HSC1_BOM2R1590<Part Number>R0402-02015%HSC1_BOM2PC110.22UF<Part Number>C0402-020125VX7RHSC1_BOM2PC5591UFC1206_H66<Part Number>100VX7RHSC1_BOM2PC560 1000PFC0402-020150VNI<Part Number>X7RPR69322.43K<Part Number>1%R0402-0201HSC1_BOM2PC101UF<Part Number>C0402-020125VX6SHSC1_BOM2R1524.7K<Part Number>R0402-02015%NIPC5621UFC060325VX7R<Part Number>HSC1_BOM2PR495.3K<Part Number>R0805_H261%HSC1_BOM2PR9310K1%R0402-0201<Part Number>HSC1_BOM2P52V_HS1_UVHP52V_HS1_VCCP52V_HS1_PWRGINP52V_HS1_ISETP52V_HS1_ISTARTP52V_HS1_VCPP52V_HS1_TEMPPP52V_HS1_TEMPNP52V_HS1_VCAPPWRGD_P52V_HS1_PGP52V_HS1_MCBP52V_HS1_ADR0P52V_HS1_GPO1P52V_HS1_ADR1P52V_HS1_GPO2SMB_CM_HS1_3V3SB_DATISMB_CM_HS1_3V3SB_DATOP52V_HS1_VREGP52V_HS1_RND
P52V_HS1_DV_DT_R
P52V_HS1_EFAULT_R
P52V_HS1_ESTART_R
P52V_HS1_DV_DTP52V_HS1_ESTARTP52V_HS1_EFAULTSMB_P52V_VPDB_SCL_R2SMB_P52V_HSC_SDASMB_P52V_HSC_SCLSMB_P52V_VPDB_SCL_R2P52V_HS1_GPO2P52V_HS1_FLTP52V_HS1_GPO1P52V_HS1_FLTP52V_HS1_ADR0P52V_HS1_ADR1



5
5
4
4
3
3
2
2
1
1
D D
C C
B B
A A
PR10 (5.9K) for LTC4287     (2.21K) for ADM1272PR9  (4.42K) for LTC4287     (1.65K) for ADM1272
CO-LAYOUT
CO-LAYOUT
46V~52V.
Power team Dubug Header
The jumper should not beplaced on header JP2
46V~52V.
P52V_HS1_4287_GATE_R25P52V_HS1_4287_GATE2_R25P52V_HS1_1272_GATE26 P52V_HS1_Drain_1 27P52V_HS1_Drain_2 27
P52V_HS1_Drain_1 27P52V_HS1_Drain_2 27
P52V_HS_1272_S_N26P52V_HS_1272_S_P26P52V_1_FUSE_1 27P52V_HS1_OV 25,26P52V_HS1_UVLO_EN 25,26P52V_HS1_TEMP25P52V_HS1_TEMPP26P52V_HS1_TEMPN26P52V_1_FUSE_127 SMB_P52V_HSC_SDA 10,25,26SMB_P52V_HSC_SCL 10,25,26P52V_HS_4287_ADC_N 25P52V_HS_4287_ADC_P25P52V_HS_4287_S1N25P52V_HS_4287_S1P 25P52V_HS_4287_S2P 25P52V_HS_4287_S2N25P52V_BUSBAR23P52V_HS1_EN 35
P52V_1P52V_1GND_FIELD_SIGNALGND_FIELD_SIGNALP52V_HSP52V_1_RP3V3_ANDP3V3_ANDSizeDoc NumberRevDate: SheetofReviewerDesignerDepartmentProject
Page TitleBU9<Doc> AC Thursday, August 24, 2023<Designer><Reviewer> 27 39<Title><Page Title>SizeDoc NumberRevDate: SheetofReviewerDesignerDepartmentProject
Page TitleBU9<Doc> AC Thursday, August 24, 2023<Designer><Reviewer> 27 39<Title><Page Title>SizeDoc NumberRevDate: SheetofReviewerDesignerDepartmentProject
Page TitleBU9<Doc> AC Thursday, August 24, 2023<Designer><Reviewer> 27 39<Title><Page Title>
PR696010R0603_H241%<Part Number>HSC1_BOM2PQ15MMBT3904-7-FBEC
PQ6PSMN3R7-100BSE  <Part Number>DGSPR102.21K1%<Part Number>R0402-0201PR695410R0603_H241%<Part Number>HSC1_BOM1JP3CONN3_HBB1037-L300D-8H123
PQ3PSMN3R7-100BSE  <Part Number>DGSR586005%R0402-02011/16WHSC1_BOM2PR8 10R0603_H24 1%0.0003PR315<Part Number>R2725_4P4W1%CHIP2B1B2A1AC900.1UF10%16VC0402-0201X7RPR5864 2001/16WR0402-02011%<Part Number>NIPR695910R0603_H241%<Part Number>HSC1_BOM2PD8B380-13-F<Part Number>AC
PR6966 100<Part Number>1%1/16W R0402HSC1_BOM1
PR395.3K<Part Number>R0805_H261%  R5884174K1%R0805_H26<Part Number>
R586105%R0402-02011/16WHSC1_BOM2PR695810R0603_H241%<Part Number>HSC1_BOM2PC10.1UFC0402-0201<Part Number>25VX7RFS120A/125V12 PR6972 2001/16WR0402-02011%<Part Number>NI
PR12 10R0603_H24 1%PD760V/51.70A<Part Number>AC 0.0003PR1<Part Number>R2725_4P4W1%CHIP2B1B2A1APQ4PSMN3R7-100BSE  <Part Number>DGSPR69631R0603_H241%<Part Number>HSC1_BOM1PR69561R0603_H241%<Part Number>HSC1_BOM1
PR69690HSC1_BOM1R588995.3K<Part Number>R0805_H261%PR13 10R0603_H24 1%
PR69730<Part Number>R0402-0201 5%R588511.5K<Part Number>R0402-02011%R58888.45K1%1/16WR0402-0201<Part Number>PR695710R0603_H241%<Part Number>HSC1_BOM1PQ1PSMN3R7-100BSE  <Part Number>DGS
R5886174K1%R0805_H26<Part Number>U1974LVC1G08W5-7A1B2GND3Y4VCC5 PR696210R0603_H241%<Part Number>HSC1_BOM1PR31333<Part Number>R0402-0201 1%
R5863 05%R0402-0201 1/16WHSC1_BOM1
C690.01UF10%100VC0603
R5862 05%R0402-0201 1/16WHSC1_BOM1PR14 10R0603_H24 1%PQ5PSMN3R7-100BSE  <Part Number>DGSPR69641R0603_H241%<Part Number>HSC1_BOM1PC20.1UFC0402-0201<Part Number>25VX7RPR696110R0603_H241%<Part Number>HSC1_BOM2PR69551R0603_H241%<Part Number>HSC1_BOM1PR91.65K1%R0402-0201<Part Number>C890.01UF10%100VC0603PR696510R0603_H241%<Part Number>HSC1_BOM1PR920<Part Number>R0402-0201 5%PR6967 0HSC1_BOM2
PQ2PSMN3R7-100BSE  <Part Number>DGSPR16 10R0603_H24 1%PD660V/51.70A<Part Number>AC
PR69680HSC1_BOM2R588711.5K<Part Number>R0402-02011%
PR295.3K<Part Number>R0805_H261%  
JP2CONN3_HBB1037-L300D-8H123
PR15 10R0603_H24 1%P52V_HS1_GATE1P52V_HS1_GATE2P52V_HS1_GATE3P52V_HS1_GATE4P52V_HS1_GATE5P52V_HS1_GATE6P52V_HS1_GATE1_RP52V_HS1_GATE2_RP52V_HS1_SENSE_P_R1P52V_HS1_SENSE_N_R1P52V_HS1_SENSE_P_R2P52V_HS1_SENSE_N_R2P52V_1_FUSE_1P52V_HS1_OVP52V_HS1_UVLO_ENP52V_HS1_TEMPP52V_HS1_TEMPPP52V_HS1_TEMP_RP52V_HS1_TEMPN_RFM_HSC_EN_BUSBARFM_HSC_EN_FUSEFM_HSC_EN_FUSESMB_P52V_VPDB_DEBUG_SDASMB_P52V_VPDB_DEBUG_SCLFM_HSC_EN_BUSBARFM_HSC_EN_BUSBARFM_HSC_EN_FUSEP52V_HS1_ENP52V_HS1_R_EN



5
5
4
4
3
3
2
2
1
1
D D
C C
B B
A A
Put these caps close to Brick0
99989735.710045.3PMBUSaddress96104103102
107
88.769.856.210
105
Delta (Q50SN120A1NKDSF)282115101Resistor(kohm)
Delta 1300WPR67=107kohmPR67=107kohm0X690X69Address(7BIT)
Flex 1300W
ADD1Address(7BIT)ADD1
P54V TO P12V BRICK
Input voltage: 51V / Output voltage: 12.2VTDC: 250A (SWB TDC+MB TDC)Peak: 344A (SWB TDC+MB Pmax)Istep:125ASlew rate 10A/usOCP: 413A  5038W1300w*3 or 860w*4 Bricks
BRICK 0SMBBUS ADDRESS : 0X69
reserve for ESD
POP PR50 for BMR491 2511 / 858 ,Q50SN120A1NKDSF
BOM Note:1300W Brick: POP PR50860W Brick: De-pop PR50
Flex (BMR491 2511/858)Delta (Q50SN12072NNDHD)Brick_P12V0_EN_N28SMB_P52V_VPDB_SDA10,29,30,31P12V_BRICK0_ALERT_N11SMB_P52V_VPDB_SCL10,29,30,31Brick_P12V0_EN_N 28PWRGD_P52V_HS1_PG26P12V_BRICK0_PWRGD 29,34P12V_MB0_SENSE+ 29PWRGD_P52V_HS1_PG_N25P12V_BRICKP3V3_AUXP12V_BRICKP12V_BRICKP3V3_AUXP12V_BRICKP52V_HS_FILTERP52V_HS
SizeDoc NumberRevDate: SheetofReviewerDesignerDepartmentProject
Page TitleBU9<Doc> AC Thursday, August 24, 2023<Designer><Reviewer> 28 39<Title><Page Title>SizeDoc NumberRevDate: SheetofReviewerDesignerDepartmentProject
Page TitleBU9<Doc> AC Thursday, August 24, 2023<Designer><Reviewer> 28 39<Title><Page Title>SizeDoc NumberRevDate: SheetofReviewerDesignerDepartmentProject
Page TitleBU9<Doc> AC Thursday, August 24, 2023<Designer><Reviewer> 28 39<Title><Page Title>
PC3022UF<Part Number>16VC0805_H57X6S+PC402200UF16V<Part Number>OSCON12PC3522UF16V<Part Number>C0805_H57X6SR1631KR0402-0201NI<Part Number>1%+PC17100UF100V<Part Number>ALUMNI12PC212.2UFX7R<Part Number>*LF_C1206100VR1684.7K1%R0402-0201<Part Number>NIPC280.1UF<Part Number>25VC0402X7RR167 05%R0402-0201 <Part Number>
HSC1_BOM1
PC3322UF16V<Part Number>C0805_H57X6SPC3822UF16V<Part Number>C0805_H57X6S+PC412200UF16V<Part Number>OSCON12PC192.2UFX7R<Part Number>*LF_C1206100VPU2MODULE14P_Q50SN120A1NKDSF<Part Number>1Vin+2ON||OFF3Vin-4Vout-_45Vout-_56Vout+_67Vout+_710PMBDATA11PMBALT12PMBCLK8PGOOD13PMBADD9SENSE-14SENSE+R398174K<Part Number>1%1/8WR0805
HSC1_BOM1
C53100PFC0402-0201<Part Number>50VNPONIPC3122UF<Part Number>16VC0805_H57X6SPC3622UF16V<Part Number>C0805_H57X6S+PC15100UF100V<Part Number>ALUM12
D
G
S
U23DMN53D0L-7HSC1_BOM2DGSR1621KR0402-0201<Part Number>1%PR58 107KR0402-0201<Part Number>1%PC222.2UFX7R<Part Number>*LF_C1206100VPC291000PF50V<Part Number>C0402X7R+PC422200UF16V<Part Number>OSCON12PC3422UF16V<Part Number>C0805_H57X6SPR593.3K1%<Part Number>R0805_H26CHIP1/8WPC202.2UFX7R<Part Number>*LF_C1206100VC51 0.1UF16V10% <Part Number>C0402-0201X7RPC3922UF16V<Part Number>C0805_H57X6SC550.1UF16V10%<Part Number>C0402-0201X7RNIR39912K<Part Number>1%1/16WR0402-0201
HSC1_BOM1
+PC16100UF100V<Part Number>ALUM12R164 05%<Part Number> R0402-0201C52100PFC0402-0201<Part Number>50VNPONIPC3222UF16V<Part Number>C0805_H57X6SPR50 05%<Part Number> R0402BRICK1_BOM1PR52 05%<Part Number> R0402-0201R165 05%<Part Number> R0402-0201R166 05%<Part Number> R0402-0201C54100PFC0402-0201<Part Number>50VNPONIR169 05%R0402-0201 <Part Number>HSC1_BOM2PC182.2UFX7R<Part Number>*LF_C1206100VPC3722UF16V<Part Number>C0805_H57X6SR160 05%<Part Number> R0402-0201R1611KR0402-0201NI<Part Number>1%PC232.2UFX7R<Part Number>*LF_C1206100VP12V_MB0_SENSE+P12V_MB0_SENSE-Brick_P12V0_ON_OFF_RSMB_P52V_VPDB_SDASMB_BRICK0_SDAP12V_BRICK0_ALERT_NSMB_BRICK0_AlertSMB_P52V_VPDB_SCLSMB_BRICK0_SCLBRICK0_PMBADDBrick_P12V0_EN_R_NP12V_BRICK0_PWRGD



5
5
4
4
3
3
2
2
1
1
D D
C C
B B
A A
Put these caps close to Brick1
10269.810ADD10X6821PR82=130kohmResistor(kohm)97PMBUSaddress103
88.7Address(7BIT)Address(7BIT)28PR82=130kohm1019835.745.3Flex (BMR491 2511/858)
104
10756.2ADD1105
Flex 1300W
0X6815
Delta 1300W 9910096Delta (Q50SN120A1NKDSF)
P54V TO P12V BRICK
BRICK 1SMBBUS ADDRESS : 0X6A
reserve for ESD
BMR491 2511 / 858 , Q50SN120A1NKDSF: PR65 INSERTBMR350 2250/501,Q50SN12072NNDHD: PR65 NOT INSERT, PR324 INSERT
BOM Note:1300W Brick: POP PR65De-pop: PR324
860W Brick: De-pop PR65pop PR324
PR73 need to change to CS38872FB04 (EF part)Delta (Q50SN12072NNDHD)Brick_P12V_1_EN_N29,30,31SMB_P52V_VPDB_SDA10,28,30,31P12V_BRICK1_ALERT_N11SMB_P52V_VPDB_SCL10,28,30,31P12V_BRICK_PWRGD 21,30,31,33P12V_MB0_SENSE+ 28P12V_MB1_SENSE+ 30Brick_P12V_1_EN_N 29,30,31P12V_BRICK0_PWRGD28,34P12V_BRICKP3V3_AUXP12V_BRICKP12V_BRICKP12V_BRICKP52V_HS_FILTERP3V3_AUXP3V3_AUX
SizeDoc NumberRevDate: SheetofReviewerDesignerDepartmentProject
Page TitleBU9<Doc> AC Thursday, August 24, 2023<Designer><Reviewer> 29 39<Title><Page Title>SizeDoc NumberRevDate: SheetofReviewerDesignerDepartmentProject
Page TitleBU9<Doc> AC Thursday, August 24, 2023<Designer><Reviewer> 29 39<Title><Page Title>SizeDoc NumberRevDate: SheetofReviewerDesignerDepartmentProject
Page TitleBU9<Doc> AC Thursday, August 24, 2023<Designer><Reviewer> 29 39<Title><Page Title>
R171 05%<Part Number> R0402-0201PC6522UF16V<Part Number>C0805_H57X6SPR65 05%<Part Number> R0402BRICK1_BOM1PR67 05%<Part Number> R0402-0201R172 05%<Part Number> R0402-0201+PC682200UF16V<Part Number>OSCON12 R170 05%<Part Number> R0402-0201C740.1UF16V10%<Part Number>C0402-0201X7RNIR1761KR0402-0201NI<Part Number>1%PC472.2UFX7R<Part Number>*LF_C1206100VR1741KR0402-0201NI<Part Number>1%R173 05%<Part Number> R0402-0201PC560.1UF<Part Number>25VC0402X7RPC502.2UFX7R<Part Number>*LF_C1206100V+PC692200UF16V<Part Number>OSCON12+PC43100UF100V<Part Number>ALUM12PC6622UF16V<Part Number>C0805_H57X6SC58100PFC0402-0201<Part Number>50VNPONIPC482.2UFX7R<Part Number>*LF_C1206100VPU3MODULE14P_Q50SN120A1NKDSF<Part Number>1Vin+2ON||OFF3Vin-4Vout-_45Vout-_56Vout+_67Vout+_710PMBDATA11PMBALT12PMBCLK8PGOOD13PMBADD9SENSE-14SENSE+R200 05%R0402-0201 <Part Number>
NI
D
G
S
U24DMN53D0L-7DGSPC6422UF16V<Part Number>C0805_H57X6SR202 05%R0402-0201 <Part Number>PR73 88.7KR0402-0201<Part Number>1%+PC702200UF16V<Part Number>OSCON12+PC44100UF100V<Part Number>ALUM12R1751KR0402-0201<Part Number>1%PC571000PF50V<Part Number>C0402X7RPC462.2UFX7R<Part Number>*LF_C1206100VPC512.2UFX7R<Part Number>*LF_C1206100VPR743.3K1%<Part Number>R0805_H26CHIP1/8WR20310K<Part Number>R0402-0201PC6722UF16V<Part Number>C0805_H57X6SPR324 05%<Part Number> R0402-0201NIC56 0.1UF16V10% <Part Number>C0402-0201X7RC57100PFC0402-0201<Part Number>50VNPONIR2014.7K1%R0402-0201<Part Number>NIC59100PFC0402-0201<Part Number>50VNPONI+PC45100UF100V<Part Number>ALUMNI12PC492.2UFX7R<Part Number>*LF_C1206100VP12V_MB1_SENSE+P12V_MB1_SENSE-Brick_P12V1_ON_OFF_RSMB_P52V_VPDB_SDASMB_BRICK1_SDAP12V_BRICK1_ALERT_NSMB_BRICK1_AlertP12V_BRICK_PWRGDSMB_P52V_VPDB_SCLSMB_BRICK1_SCLBRICK1_PMBADDBrick_P12V_EN_R_N



5
5
4
4
3
3
2
2
1
1
D D
C C
B B
A A
1510104
69.8
45.3Delta (Q50SN120A1NKDSF)88.7Resistor(kohm)56.2969897105100282110710199PMBUSaddress102
103
Flex (BMR491 2203/851)35.7
Flex 1300W
0X67ADD1Delta 1300WAddress(7BIT)PR94=158kohmADD1PR94=158kohmAddress(7BIT)
BRICK 2SMBBUS ADDRESS : 0X6B
Put these caps close to Brick2
0X67
P54V TO P12V BRICK
BMR491 2511 / 858 , Q50SN120A1NKDSF: PR318 INSERTBMR350 2250/501,Q50SN12072NNDHD: PR318 NOT INSERT, PR323 INSERT
BOM Note:1300W Brick: POP PR318De-pop: PR323
860W Brick: De-pop PR318pop PR323
Delta (Q50SN12072NNDHD)Brick_P12V_1_EN_N29,31SMB_P52V_VPDB_SDA10,28,29,31P12V_BRICK2_ALERT_N11 P12V_BRICK_PWRGD 21,29,31,33SMB_P52V_VPDB_SCL10,28,29,31P12V_MB1_SENSE+ 29P12V_MB2_SENSE+ 31P52V_HS_FILTERP12V_BRICKP3V3_AUXP12V_BRICKP12V_BRICKP12V_BRICK
SizeDoc NumberRevDate: SheetofReviewerDesignerDepartmentProject
Page TitleBU9<Doc> AC Thursday, August 24, 2023<Designer><Reviewer> 30 39<Title><Page Title>SizeDoc NumberRevDate: SheetofReviewerDesignerDepartmentProject
Page TitleBU9<Doc> AC Thursday, August 24, 2023<Designer><Reviewer> 30 39<Title><Page Title>SizeDoc NumberRevDate: SheetofReviewerDesignerDepartmentProject
Page TitleBU9<Doc> AC Thursday, August 24, 2023<Designer><Reviewer> 30 39<Title><Page Title>
R197 05%<Part Number> R0402-0201+PC114100UF100V<Part Number>ALUM12PC1172.2UFX7R<Part Number>*LF_C1206100VPC1220.1UF<Part Number>25VC0402X7RPU6MODULE14P_Q50SN120A1NKDSF<Part Number>1Vin+2ON||OFF3Vin-4Vout-_45Vout-_56Vout+_67Vout+_710PMBDATA11PMBALT12PMBCLK8PGOOD13PMBADD9SENSE-14SENSE+PC12722UF16V<Part Number>C0805_H57X6S+PC1352200UF16V<Part Number>OSCON12C72100PFC0402-0201<Part Number>50VNPONIPC13222UF16V<Part Number>C0805_H57X6S+PC115100UF100V<Part Number>ALUMNI12PC1202.2UFX7R<Part Number>*LF_C1206100VR1931KR0402-0201<Part Number>1%PR319 05%<Part Number> R0402-0201R198 05%<Part Number> R0402-0201R196 05%<Part Number> R0402-0201+PC1362200UF16V<Part Number>OSCON12PC1182.2UFX7R<Part Number>*LF_C1206100VC70 0.1UF16V10% <Part Number>C0402-0201X7RR195 05%<Part Number> R0402-0201PR323 05%<Part Number> R0402-0201NIPC1231000PF50V<Part Number>C0402X7RPR3213.3K1%<Part Number>R0805_H26CHIP1/8WPR318 05%<Part Number> R0402BRICK1_BOM1PC12822UF16V<Part Number>C0805_H57X6SPC13322UF16V<Part Number>C0805_H57X6SPC1162.2UFX7R<Part Number>*LF_C1206100V+PC113100UF100V<Part Number>ALUM12 PR320 69.8KR0402-0201<Part Number>1%R1941KR0402-0201NI<Part Number>1%PC1212.2UFX7R<Part Number>*LF_C1206100VC71100PFC0402-0201<Part Number>50VNPONIC73100PFC0402-0201<Part Number>50VNPONIR1921KR0402-0201NI<Part Number>1%+PC1342200UF16V<Part Number>OSCON12PC1192.2UFX7R<Part Number>*LF_C1206100VP12V_MB2_SENSE+P12V_MB2_SENSE-Brick_P12V2_ON_OFF_RSMB_P52V_VPDB_SDASMB_BRICK2_SDAP12V_BRICK2_ALERT_NSMB_BRICK2_AlertP12V_BRICK_PWRGDSMB_P52V_VPDB_SCLSMB_BRICK2_SCLBRICK2_PMBADD



5
5
4
4
3
3
2
2
1
1
D D
C C
B B
A A
Flex 1300W
0X66ADD1Delta 1300WAddress(7BIT)PR94=158kohmADD1PR94=158kohmAddress(7BIT)
P54V TO P12V BRICK
BRICK 3SMBBUS ADDRESS : 0X6B
Put these caps close to Brick2
0X66
BRICK 3 is reverse for 860w brick solution(note: HSC1_BOM2)
151010469.845.3Delta (Q50SN120A1NKDSF)88.7Resistor(kohm)
56.2
969897105100282110710199PMBUSaddress
102
10335.7Flex (BMR491 2511/858)
BOM Note:1300W Brick: De-pop PR78De-pop: PR322
860W Brick: De-pop PR78pop PR322
Delta (Q50SN12072NNDHD)P12V_MB2_SENSE+ 30Brick_P12V_1_EN_N29,30SMB_P52V_VPDB_SDA10,28,29,30P12V_BRICK3_ALERT_N11 P12V_BRICK_PWRGD 21,29,30,33SMB_P52V_VPDB_SCL10,28,29,30P52V_HS_FILTERP12V_BRICKP3V3_AUXP12V_BRICKP12V_BRICKP12V_BRICK
SizeDoc NumberRevDate: SheetofReviewerDesignerDepartmentProject
Page TitleBU9<Doc> AC Thursday, August 24, 2023<Designer><Reviewer> 31 39<Title><Page Title>SizeDoc NumberRevDate: SheetofReviewerDesignerDepartmentProject
Page TitleBU9<Doc> AC Thursday, August 24, 2023<Designer><Reviewer> 31 39<Title><Page Title>SizeDoc NumberRevDate: SheetofReviewerDesignerDepartmentProject
Page TitleBU9<Doc> AC Thursday, August 24, 2023<Designer><Reviewer> 31 39<Title><Page Title>
PC840.1UF<Part Number>25VC0402X7RBRICK1_BOM2PR863.3K1%<Part Number>R0805_H26CHIP1/8WBRICK1_BOM2PU4MODULE14P_Q50SN120A1NKDSF<Part Number>BRICK1_BOM21Vin+2ON||OFF3Vin-4Vout-_45Vout-_56Vout+_67Vout+_710PMBDATA11PMBALT12PMBCLK8PGOOD13PMBADD9SENSE-14SENSE+PC752.2UFX7R<Part Number>*LF_C1206100VBRICK1_BOM2C62100PFC0402-0201<Part Number>50VNPONIR178 05%<Part Number> R0402-0201BRICK1_BOM2PC772.2UFX7R<Part Number>*LF_C1206100VBRICK1_BOM2+PC73100UF100V<Part Number>ALUMNI12PC8622UF<Part Number>16VC0805_H57X6SR179 05%<Part Number> R0402-0201BRICK1_BOM2+PC972200UF16V<Part Number>OSCONBRICK1_BOM212PC9122UF16V<Part Number>C0805_H57X6SPC792.2UFX7R<Part Number>*LF_C1206100VBRICK1_BOM2PR78 05%<Part Number> R0402NI+PC71100UF100V<Part Number>ALUMBRICK1_BOM212 PR325 56.2K<Part Number>1%1/16W R0402-0201BRICK1_BOM2PC8922UF16V<Part Number>C0805_H57X6SR1831KR0402-0201NI<Part Number>1%PC9422UF16V<Part Number>C0805_H57X6SPR322 05%<Part Number> R0402-0201BRICK1_BOM2PC742.2UFX7R<Part Number>*LF_C1206100VBRICK1_BOM2PC8722UF<Part Number>16VC0805_H57X6S+PC982200UF16V<Part Number>OSCONBRICK1_BOM212PC9222UF16V<Part Number>C0805_H57X6SC61100PFC0402-0201<Part Number>50VNPONIR1811KR0402-0201NI<Part Number>1%PC762.2UFX7R<Part Number>*LF_C1206100VBRICK1_BOM2PC851000PF50V<Part Number>C0402X7RBRICK1_BOM2C63100PFC0402-0201<Part Number>50VNPONIPC782.2UFX7R<Part Number>*LF_C1206100VBRICK1_BOM2PR79 05%<Part Number> R0402-0201BRICK1_BOM2+PC72100UF100V<Part Number>ALUMBRICK1_BOM212+PC962200UF16V<Part Number>OSCONBRICK1_BOM212PC9022UF16V<Part Number>C0805_H57X6SR177 05%<Part Number> R0402-0201BRICK1_BOM2PC9522UF16V<Part Number>C0805_H57X6SPC8822UF16V<Part Number>C0805_H57X6SC60 0.1UF16V10% <Part Number>C0402-0201X7RBRICK1_BOM2R180 05%<Part Number> R0402-0201BRICK1_BOM2R1821KR0402-0201BRICK1_BOM2<Part Number>1%PC9322UF16V<Part Number>C0805_H57X6SP12V_MB3_SENSE+P12V_MB3_SENSE-Brick_P12V3_ON_OFF_RSMB_P52V_VPDB_SDASMB_BRICK3_SDAP12V_BRICK3_ALERT_NSMB_BRICK3_AlertP12V_BRICK_PWRGDSMB_P52V_VPDB_SCLSMB_BRICK3_SCLBRICK3_PMBADD



5
5
4
4
3
3
2
2
1
1
D D
C C
B B
A A
L-C FILTER
P52V_HSP52V_HSP52V_HSP52V_HS_FILTERP52V_HS_FILTERP52V_HS_FILTERSizeDoc NumberRevDate: SheetofReviewerDesignerDepartmentProject
Page TitleBU9<Doc> AB Thursday, August 24, 2023<Designer><Reviewer> 32 39<Title><Page Title>SizeDoc NumberRevDate: SheetofReviewerDesignerDepartmentProject
Page TitleBU9<Doc> AB Thursday, August 24, 2023<Designer><Reviewer> 32 39<Title><Page Title>SizeDoc NumberRevDate: SheetofReviewerDesignerDepartmentProject
Page TitleBU9<Doc> AB Thursday, August 24, 2023<Designer><Reviewer> 32 39<Title><Page Title>
C232.2UFX7R<Part Number>10%C222.2UFX7R<Part Number>10%C452.2UFX7R<Part Number>10%L11.5UH<Part Number>53A21C302.2UFX7R<Part Number>10%C262.2UFX7R<Part Number>10%C412.2UFX7R<Part Number>10%C352.2UFX7R<Part Number>10%C292.2UFX7R<Part Number>10%C312.2UFX7R<Part Number>10%C242.2UFX7R<Part Number>10%C422.2UFX7R<Part Number>10%C362.2UFX7R<Part Number>10%L51.5UH<Part Number>53A21C272.2UFX7R<Part Number>10%C382.2UFX7R<Part Number>10%C322.2UFX7R<Part Number>10%C432.2UFX7R<Part Number>10%C372.2UFX7R<Part Number>10%C252.2UFX7R<Part Number>10%C392.2UFX7R<Part Number>10%L31.5UH<Part Number>53A21C332.2UFX7R<Part Number>10%C442.2UFX7R<Part Number>10%C282.2UFX7R<Part Number>10%C402.2UFX7R<Part Number>10%C342.2UFX7R<Part Number>10%



5
5
4
4
3
3
2
2
1
1
D D
C C
B B
A A
P12V CURRENT LIMIT
Current=2.68A(max)OCP= 3.48A
MP5025C/
MP5022C
Pop
De-pop
U32 optional BOM
MP5025A/
MP5022A
R5895 De-pop
R5896 De-pop
Pop
Pop
Pop
De-popC95
R5893
Pop
De-pop
R5894
RS31312
Pop
Pop
De-pop
De-pop
Pop
P12V_HPDB_PWRGD 11,24P12V_BRICK_PWRGD21,29,30,31P12V_BRICKP3V3_AUXP12V_HPDBP12V_BRICKP3V3_AUXSizeDoc NumberRevDate: SheetofReviewerDesignerDepartmentProject
Page TitleBU9<Doc> AC Thursday, August 24, 2023<Designer><Reviewer> 33 39<Title><Page Title>SizeDoc NumberRevDate: SheetofReviewerDesignerDepartmentProject
Page TitleBU9<Doc> AC Thursday, August 24, 2023<Designer><Reviewer> 33 39<Title><Page Title>SizeDoc NumberRevDate: SheetofReviewerDesignerDepartmentProject
Page TitleBU9<Doc> AC Thursday, August 24, 2023<Designer><Reviewer> 33 39<Title><Page Title>
R589671.5K1%R0402<Part Number>NIC911UFX6S25VC0402<Part Number>R589549.91%<Part Number>R0603C9210UFX6S25VC0805_H61<Part Number>R5897 10K1% R0402-0201<Part Number>R590137.4K<Part Number>1%R0402-0201R5892 1K1% R0402-0201<Part Number>R589910K1%R0402-0201<Part Number>C930.1UFX7R25VC0402<Part Number>C940.22UFX7R25VC0402-0201<Part Number>C952.2UFX7R16VC0603_H40<Part Number>R590220K1%1/16W<Part Number>R0402-0201R590046.4K1%R0402-0201<Part Number>D4SMBJ14A<Part Number>ACC98560PF50VX7RC0402-0201R58931001%R0402<Part Number>NIR589110K1%R0402-0201<Part Number>C97100NF50V<Part Number>X7RC0402-0201R5894120K<Part Number>R04021%U32MP5022CGQV-Z<Part Number>VOUT_2020VIN_21_2221_22VOUT_1919VOUT_1818VOUT_1717VOUT_1616VOUT_1515VOUT_1414AVIN12VOUT_1313OV11PG10FLTB9IMON8VIN_2323VIN_2424VIN_2525VIN_2626EN1LOADEN2ENTM3TIMER4ISET5SS6GND7C960.047UFX7R25VC0402-0201<Part Number>D5B340A-13-F<Part Number>ACP12V_HPDB_0_EN_RP12V_HPDB_0_PDP12V_HPDB_0_TIMERP12V_HPDB_0_FBP12V_HPDB_0_PDP12V_HPDB_0_ISETP12V_HPDB_0_SSP12V_HPDB_0_FLTBP12V_HPDB_0_IMONP12V_HPDB_0_ISET_R



5
5
4
4
3
3
2
2
1
1
D D
C C
B B
A A
DCR= 5mΩRated Current= 5A 
Ra
Rb
Ven<3.6V
DCR= 40mΩIsat= 10A6.5*6.9*3mm
Open Drain 4.3V (Max)
Vo=0.6(1+Ra/Rb) = 3.3V
Enable:Vth > 1.27V (Max)
Output Voltage = 3.3V±5%Output Ripple & Noise < 30mVTransient Tolerance = 330mVTDC = TBDMax current = 2.55AOver-Current Protection =3.2A (1.3*Max)Current Step =1.25ASlew Rate = 2.5A/usWork frequency = 600KHZEfficiency > 85% @TDC
Design specification
P3V3_AUX
PC111 need change to (150P) for TIC 2nd source
PR314 need change to 0OHM for 2nd/3rd source
P12V_BRICK0_PWRGD28,29P12V_BRICKP3V3_AUXP3V3_AUX
SizeDoc NumberRevDate: SheetofReviewerDesignerDepartmentProject
Page TitleBU9<Doc> AC Thursday, August 24, 2023<Designer><Reviewer> 34 39<Title><Page Title>SizeDoc NumberRevDate: SheetofReviewerDesignerDepartmentProject
Page TitleBU9<Doc> AC Thursday, August 24, 2023<Designer><Reviewer> 34 39<Title><Page Title>SizeDoc NumberRevDate: SheetofReviewerDesignerDepartmentProject
Page TitleBU9<Doc> AC Thursday, August 24, 2023<Designer><Reviewer> 34 39<Title><Page Title>PR90 56K<Part Number>1%PC10722UF6.3VX6S*LF_C0805<Part Number>PC56822UF16VX6SC0805_H57<Part Number>PR8860.4KR0402-0201<Part Number>PC56622UF16VX6SC0805_H57<Part Number>PC99100NF<Part Number>50VX7RC0402PC10522UF6.3VX6S*LF_C0805<Part Number>PR8910.5K<Part Number>1/16WR0402-02011%PC1091UFX6S25VC0402-0201<Part Number>R8310K<Part Number>1%1/16WPR9112.4KR0402-02011%<Part Number>PC102100NF<Part Number>50VX7RC0402PC10822UF<Part Number>6.3VC0805_H61X6SPC111 100PF50V<Part Number> C0402-0201 NPOPC56722UF16VX6SC0805_H57<Part Number>PC10022UF16VX6SC0805_H57<Part Number>PC1103300PFC0402-020150VX7R<Part Number>PC10622UF6.3VX6S*LF_C0805<Part Number>PU5MPQ8626GD-ZQFN14_0-5_3X2XA<Part Number>VIN3PGOOD9PGND214EN5BST10FB6AGND7VCC13PGND11SW211TRK_REF8MODE12CS4SW12PL24.7U<Part Number>PCMC063T-4R7MN21PC104100NFX7RC0402-0201<Part Number>50VPC1030.22UFC0402-020125VX7R<Part Number>PC1120.22UF<Part Number>25VC0402-0201X7RPR314 2.21% 1/16W<Part Number>PL1BLM18SN220TN1DL0603<Part Number>21PC10122UF16VX6S<Part Number>C0805_H57R8253.6K1%1/16W<Part Number>PR8710K<Part Number>R0402-0201P3V3_AUX_PWRGDSW_P3V3_AUX_BTSW_P3V3_AUX_BT_RSW_P3V3_AUX_PHP12V_BRICK0_PWRGDP3V3_AUX_MODEP3V3_AUX_VCCP3V3_AUX_FBP3V3_AUX_REFP3V3_AUX_CSSW_P12V_FILT__P3V3_AUX



5
5
4
4
3
3
2
2
1
1
D D
C C
B B
A A
AC POWER BUTTON
delay 1msdelay ~6sdelay 48.7msR5917 VALUE TBDFM_AC_PWR_CYCLE_N21 P52V_HS1_EN27P52V_HS1_EN_BUF_DELAY 25,26P52V_1_RP52V_1_RP52V_1_RP52V_1_R
SizeDoc NumberRevDate: SheetofReviewerDesignerDepartmentProject
Page TitleBU9<Doc> AC Thursday, August 24, 2023<Designer><Reviewer> 35 39<Title><Page Title>SizeDoc NumberRevDate: SheetofReviewerDesignerDepartmentProject
Page TitleBU9<Doc> AC Thursday, August 24, 2023<Designer><Reviewer> 35 39<Title><Page Title>SizeDoc NumberRevDate: SheetofReviewerDesignerDepartmentProject
Page TitleBU9<Doc> AC Thursday, August 24, 2023<Designer><Reviewer> 35 39<Title><Page Title>
R5910174K1%R0805_H26<Part Number>R591611.5K<Part Number>R0402-02011%
D
G
S
U37DMN53D0L-7<Part Number>DGSC10122UF<Part Number>16VC0805_H57X6S
D
G
S
U39DMN53D0L-7<Part Number>DGSR5932174K1%R0805_H26<Part Number>R591111.5K<Part Number>R0402-02011%D11B340A-13-F<Part Number>ACR5918 2.05MR0805_H261%<Part Number>R5919 48.7K1%R0402-0201<Part Number>R5930174K1%R0805_H26<Part Number>C1021UFX6S25VC0402-0201<Part Number>D12B340A-13-F<Part Number>ACR593311.5K<Part Number>R0402-02011%D6SDMK0340L-7-F12C1001UFX6S25VC0402-0201<Part Number>R5917 1KR0402-02011% 1/16W
D
G
S
U36DMN53D0L-7<Part Number>DGSR5915174K1%R0805_H26<Part Number>
D
G
S
U40DMN53D0L-7<Part Number>DGSR593111.5K<Part Number>R0402-02011%FM_AC_PWR_CYCLE_R1_NFM_AC_PWR_CYCLE_BUFP52V_HS1_EN_DELAYFM_AC_PWR_CYCLE_R_BUFP52V_HS1_EN_DELAY_NP52V_HS1_EN_DELAYP52V_HS1_EN_BUF_DELAY



5
5
4
4
3
3
2
2
1
1
D D
C C
B B
A A
LOSS COUPON
5 inch trace 10 inch trace
SizeDoc NumberRevDate: SheetofReviewerDesignerDepartmentProject
Page TitleBU9<Doc> AB Thursday, August 24, 2023<Designer><Reviewer> 36 39<Title><Page Title>SizeDoc NumberRevDate: SheetofReviewerDesignerDepartmentProject
Page TitleBU9<Doc> AB Thursday, August 24, 2023<Designer><Reviewer> 36 39<Title><Page Title>SizeDoc NumberRevDate: SheetofReviewerDesignerDepartmentProject
Page TitleBU9<Doc> AB Thursday, August 24, 2023<Designer><Reviewer> 36 39<Title><Page Title>



5
5
4
4
3
3
2
2
1
1
D D
C C
B B
A A
DUMMY SYMBOLS
Quanta LOGO(TOP)
PN LABEL
Laser Mark(TOP) Laser Mark(BOT)
PB-E1WEEE SN LABELPCBA_LABEL
CE UL
vendor logo
SizeDoc NumberRevDate: SheetofReviewerDesignerDepartmentProject
Page TitleBU9<Doc> AB Thursday, August 24, 2023<Designer><Reviewer> 37 39<Title><Page Title>SizeDoc NumberRevDate: SheetofReviewerDesignerDepartmentProject
Page TitleBU9<Doc> AB Thursday, August 24, 2023<Designer><Reviewer> 37 39<Title><Page Title>SizeDoc NumberRevDate: SheetofReviewerDesignerDepartmentProject
Page TitleBU9<Doc> AB Thursday, August 24, 2023<Designer><Reviewer> 37 39<Title><Page Title>
ME_PART SymbolME1PB-E1_SMALLME_PART SymbolME4SNLABEL_7X7ME_PART SymbolDM1PNLABEL_23-5X5ME_PART SymbolME2WEEEME_PART SymbolME3QUANTA_LOGO_7X26ME_PART SymbolME5PCB_VENDOR_LOGO_15X8



5
5
4
4
3
3
2
2
1
1
D D
C C
B B
A A
SCREW HOLES
THUMB SCREW HOLE
GOURD SCREW HOLE
Tooling Holes
NUT HOLE
SizeDoc NumberRevDate: SheetofReviewerDesignerDepartmentProject
Page TitleBU9<Doc> AB Thursday, August 24, 2023<Designer><Reviewer> 38 39<Title><Page Title>SizeDoc NumberRevDate: SheetofReviewerDesignerDepartmentProject
Page TitleBU9<Doc> AB Thursday, August 24, 2023<Designer><Reviewer> 38 39<Title><Page Title>SizeDoc NumberRevDate: SheetofReviewerDesignerDepartmentProject
Page TitleBU9<Doc> AB Thursday, August 24, 2023<Designer><Reviewer> 38 39<Title><Page Title>H20HOLE_C10-16D6-4B10_OB22XC5B_NP<Part Number>H14HOLE_C10D3_5B10_OB22XC5_NPM_TEAR_SPD<Part Number>H19HOLE_C10-16D6-4B10_OB22XC5B_NP<Part Number>H24HOLE_C8D4-22B8I6-02_RO7-02_NPT_RB<Part Number>H21HOLE_TOOLINGD125N_T2-0H11HOLE_C10D3_5B10_OB22XC5_NPM_TEAR_SPD<Part Number>H16HOLE_C10D3_5B10_OB22XC5_NPM_TEAR_SPD<Part Number>H4HOLE_C10D3_5B10_OB22XC5_NPM_TEAR_SPD<Part Number>H25HOLE_C8D4-22B8I6-02_RO7-02_NPT_RB<Part Number>H22HOLE_TOOLINGD125N_T2-0H2HOLE_C10D3_5B10_OB22XC5_NPM_TEAR_SPD<Part Number>H18HOLE_C10D3_5B10_OB22XC5_NPM_TEAR_SPD<Part Number>H23HOLE_TOOLINGD125N_T2-0H24_TPH25_TP



5
5
4
4
3
3
2
2
1
1
D D
C C
B B
A A
TDR
BOT
TOP
IN1
IN2
SizeDoc NumberRevDate: SheetofReviewerDesignerDepartmentProject
Page TitleBU9<Doc> AA Thursday, August 24, 2023<Designer><Reviewer> 39 39<Title><Page Title>SizeDoc NumberRevDate: SheetofReviewerDesignerDepartmentProject
Page TitleBU9<Doc> AA Thursday, August 24, 2023<Designer><Reviewer> 39 39<Title><Page Title>SizeDoc NumberRevDate: SheetofReviewerDesignerDepartmentProject
Page TitleBU9<Doc> AA Thursday, August 24, 2023<Designer><Reviewer> 39 39<Title><Page Title>J11TDR_3P_C85P67_141_100M_QGND1IO12IO23J12TDR_3P_C85P67_141_100M_QGND1IO12IO23J13TDR_3P_C85P67_141_100M_QGND1IO12IO23J10TDR_3P_C85P67_141_100M_QGND1IO12IO23TDR_SE_50_OHM_TOPTDR_SE_50_OHM_IN1TDR_SE_50_OHM_IN2TDR_SE_50_OHM_BOT